# T6G (Grand Teton) — schematic netlist excerpt (pin names and nets, part order shuffled) for the footprints in the layout excerpt that follows; sources: Cadence DE-HDL packaged netlist, KiCad conversion of 04192023_DAF0TMB3IC0_F0TG_MB_C_brd_V02_OCP.brd

R6295  Q_RES  0 5% CHIP  pkg 0402LF  page 178 : A = USB_HUB2_TI_OVERCCUR4 ; B = USB_HUB2_TI_OVERCUR4_MRP_I2C_SLV_CFG1
C724  Q_CAP_DIFFBUS  DIFF BUS_0.22UF 6.3V 20% X6S  pkg C0201  page 66 : \1\ = P5E_CPU1_P1_TX_C_DN<8> ; \2\ = P5E_CPU1_P1_TX_DN<8>
R3775  Q_RES  0 5% CHIP  pkg 0402LF  page 145 : A = FM_SMB_RST_E1S_0_R_N ; B = RST_SMB_E1S_N

(kicad_pcb
	(version 20260206)
	(generator "pcbnew")
	(generator_version "10.0")
	(general
		(thickness 1.6)
		(legacy_teardrops no)
	)
	(paper "A4")
	(title_block
		(title "04192023_DAF0TMB3IC0_F0TG_MB_C_brd_V02_OCP.brd")
		(comment 1 "Grand Teton / footprints 4872-4874 of 8354")
	)
	(layers
		(0 "F.Cu" signal "TOP")
		(4 "In1.Cu" signal "GND")
		(6 "In2.Cu" signal "IN1")
		(8 "In3.Cu" signal "GND1")
		(10 "In4.Cu" signal "IN2")
		(12 "In5.Cu" signal "GND2")
		(14 "In6.Cu" signal "IN3")
		(16 "In7.Cu" signal "GND3")
		(18 "In8.Cu" signal "VCC")
		(20 "In9.Cu" signal "VCC1")
		(22 "In10.Cu" signal "GND4")
		(24 "In11.Cu" signal "IN4")
		(26 "In12.Cu" signal "GND5")
		(28 "In13.Cu" signal "IN5")
		(30 "In14.Cu" signal "GND6")
		(32 "In15.Cu" signal "IN6")
		(34 "In16.Cu" signal "GND7")
		(2 "B.Cu" signal "BOTTOM")
		(9 "F.Adhes" user "F.Adhesive")
		(11 "B.Adhes" user "B.Adhesive")
		(13 "F.Paste" user "Package Geometry/Pastemask Top")
		(15 "B.Paste" user "Package Geometry/Pastemask Bottom")
		(5 "F.SilkS" user "Ref Des/Silkscreen Top")
		(7 "B.SilkS" user "Ref Des/Silkscreen Bottom")
		(1 "F.Mask" user "Board Geometry/Soldermask Top")
		(3 "B.Mask" user "Board Geometry/Soldermask Bottom")
		(17 "Dwgs.User" user "User.Drawings")
		(19 "Cmts.User" user "User.Comments")
		(21 "Eco1.User" user "User.Eco1")
		(23 "Eco2.User" user "User.Eco2")
		(25 "Edge.Cuts" user "Board Geometry/Outline")
		(27 "Margin" user)
		(31 "F.CrtYd" user "Package Geometry/Place Bound Top")
		(29 "B.CrtYd" user "Package Geometry/Place Bound Bottom")
		(35 "F.Fab" user "Ref Des/Assembly Top")
		(33 "B.Fab" user "Ref Des/Assembly Bottom")
	)
	(footprint ""
		(layer "F.Cu")
		(at 115.010946 -52.48148 180)
		(property "Reference" "R6295"
			(at 0 0 180)
			(layer "F.SilkS")
			(hide yes)
			(effects
				(font
					(size 1.27 1.27)
				)
			)
		)
		(property "Value" ""
			(at 0 0 180)
			(layer "F.Fab")
			(effects
				(font
					(size 1.27 1.27)
				)
			)
		)
		(duplicate_pad_numbers_are_jumpers no)
		(fp_line
			(start 0.7874 0.4064)
			(end -0.7874 0.4064)
			(stroke
				(width 0.1524)
				(type default)
			)
			(layer "F.SilkS")
		)
		(fp_line
			(start 0.7874 -0.4064)
			(end 0.7874 0.4064)
			(stroke
				(width 0.1524)
				(type default)
			)
			(layer "F.SilkS")
		)
		(fp_line
			(start -0.7874 0.4064)
			(end -0.7874 -0.4064)
			(stroke
				(width 0.1524)
				(type default)
			)
			(layer "F.SilkS")
		)
		(fp_line
			(start -0.7874 -0.4064)
			(end 0.7874 -0.4064)
			(stroke
				(width 0.1524)
				(type default)
			)
			(layer "F.SilkS")
		)
		(fp_line
			(start 0.67945 0.3048)
			(end 0.120396 0.3048)
			(stroke
				(width 0.1)
				(type default)
			)
			(layer "F.Fab")
		)
		(fp_line
			(start 0.67945 -0.3048)
			(end 0.67945 0.3048)
			(stroke
				(width 0.1)
				(type default)
			)
			(layer "F.Fab")
		)
		(fp_line
			(start 0.12065 -0.2794)
			(end 0.12065 -0.3048)
			(stroke
				(width 0.1)
				(type default)
			)
			(layer "F.Fab")
		)
		(fp_line
			(start 0.12065 -0.3048)
			(end 0.67945 -0.3048)
			(stroke
				(width 0.1)
				(type default)
			)
			(layer "F.Fab")
		)
		(fp_line
			(start 0.120396 0.3048)
			(end 0.120396 0.2794)
			(stroke
				(width 0.1)
				(type default)
			)
			(layer "F.Fab")
		)
		(fp_line
			(start 0.120396 0.2794)
			(end -0.12065 0.2794)
			(stroke
				(width 0.1)
				(type default)
			)
			(layer "F.Fab")
		)
		(fp_line
			(start -0.12065 0.3048)
			(end -0.67945 0.3048)
			(stroke
				(width 0.1)
				(type default)
			)
			(layer "F.Fab")
		)
		(fp_line
			(start -0.12065 0.2794)
			(end -0.12065 0.3048)
			(stroke
				(width 0.1)
				(type default)
			)
			(layer "F.Fab")
		)
		(fp_line
			(start -0.12065 -0.2794)
			(end 0.12065 -0.2794)
			(stroke
				(width 0.1)
				(type default)
			)
			(layer "F.Fab")
		)
		(fp_line
			(start -0.12065 -0.305054)
			(end -0.12065 -0.2794)
			(stroke
				(width 0.1)
				(type default)
			)
			(layer "F.Fab")
		)
		(fp_line
			(start -0.67945 0.3048)
			(end -0.67945 -0.305054)
			(stroke
				(width 0.1)
				(type default)
			)
			(layer "F.Fab")
		)
		(fp_line
			(start -0.67945 -0.305054)
			(end -0.12065 -0.305054)
			(stroke
				(width 0.1)
				(type default)
			)
			(layer "F.Fab")
		)
		(pad "1" smd circle
			(at -0.40005 0 180)
			(size 0 0)
			(layers "F.Cu" "F.Mask" "F.Paste")
			(net "USB_HUB2_TI_OVERCCUR4")
		)
		(pad "2" smd circle
			(at 0.40005 0 180)
			(size 0 0)
			(layers "F.Cu" "F.Mask" "F.Paste")
			(net "USB_HUB2_TI_OVERCUR4_MRP_I2C_SLV_CFG1")
		)
	)
	(footprint ""
		(layer "F.Cu")
		(at 250.465336 -75.092814)
		(property "Reference" "R3775"
			(at 0 0 0)
			(layer "F.SilkS")
			(hide yes)
			(effects
				(font
					(size 1.27 1.27)
				)
			)
		)
		(property "Value" ""
			(at 0 0 0)
			(layer "F.Fab")
			(effects
				(font
					(size 1.27 1.27)
				)
			)
		)
		(duplicate_pad_numbers_are_jumpers no)
		(fp_line
			(start -0.7874 -0.4064)
			(end 0.7874 -0.4064)
			(stroke
				(width 0.1524)
				(type default)
			)
			(layer "F.SilkS")
		)
		(fp_line
			(start -0.7874 0.4064)
			(end -0.7874 -0.4064)
			(stroke
				(width 0.1524)
				(type default)
			)
			(layer "F.SilkS")
		)
		(fp_line
			(start 0.7874 -0.4064)
			(end 0.7874 0.4064)
			(stroke
				(width 0.1524)
				(type default)
			)
			(layer "F.SilkS")
		)
		(fp_line
			(start 0.7874 0.4064)
			(end -0.7874 0.4064)
			(stroke
				(width 0.1524)
				(type default)
			)
			(layer "F.SilkS")
		)
		(fp_line
			(start -0.67945 -0.305054)
			(end -0.12065 -0.305054)
			(stroke
				(width 0.1)
				(type default)
			)
			(layer "F.Fab")
		)
		(fp_line
			(start -0.67945 0.3048)
			(end -0.67945 -0.305054)
			(stroke
				(width 0.1)
				(type default)
			)
			(layer "F.Fab")
		)
		(fp_line
			(start -0.12065 -0.305054)
			(end -0.12065 -0.2794)
			(stroke
				(width 0.1)
				(type default)
			)
			(layer "F.Fab")
		)
		(fp_line
			(start -0.12065 -0.2794)
			(end 0.12065 -0.2794)
			(stroke
				(width 0.1)
				(type default)
			)
			(layer "F.Fab")
		)
		(fp_line
			(start -0.12065 0.2794)
			(end -0.12065 0.3048)
			(stroke
				(width 0.1)
				(type default)
			)
			(layer "F.Fab")
		)
		(fp_line
			(start -0.12065 0.3048)
			(end -0.67945 0.3048)
			(stroke
				(width 0.1)
				(type default)
			)
			(layer "F.Fab")
		)
		(fp_line
			(start 0.120396 0.2794)
			(end -0.12065 0.2794)
			(stroke
				(width 0.1)
				(type default)
			)
			(layer "F.Fab")
		)
		(fp_line
			(start 0.120396 0.3048)
			(end 0.120396 0.2794)
			(stroke
				(width 0.1)
				(type default)
			)
			(layer "F.Fab")
		)
		(fp_line
			(start 0.12065 -0.3048)
			(end 0.67945 -0.3048)
			(stroke
				(width 0.1)
				(type default)
			)
			(layer "F.Fab")
		)
		(fp_line
			(start 0.12065 -0.2794)
			(end 0.12065 -0.3048)
			(stroke
				(width 0.1)
				(type default)
			)
			(layer "F.Fab")
		)
		(fp_line
			(start 0.67945 -0.3048)
			(end 0.67945 0.3048)
			(stroke
				(width 0.1)
				(type default)
			)
			(layer "F.Fab")
		)
		(fp_line
			(start 0.67945 0.3048)
			(end 0.120396 0.3048)
			(stroke
				(width 0.1)
				(type default)
			)
			(layer "F.Fab")
		)
		(pad "1" smd circle
			(at -0.40005 0)
			(size 0 0)
			(layers "F.Cu" "F.Mask" "F.Paste")
			(net "FM_SMB_RST_E1S_0_R_N")
		)
		(pad "2" smd circle
			(at 0.40005 0)
			(size 0 0)
			(layers "F.Cu" "F.Mask" "F.Paste")
			(net "RST_SMB_E1S_N")
		)
	)
	(footprint ""
		(layer "F.Cu")
		(at 90.046302 -373.03583 -90)
		(property "Reference" "C724"
			(at 0 0 270)
			(layer "F.SilkS")
			(hide yes)
			(effects
				(font
					(size 1.27 1.27)
				)
			)
		)
		(property "Value" ""
			(at 0 0 270)
			(layer "F.Fab")
			(effects
				(font
					(size 1.27 1.27)
				)
			)
		)
		(duplicate_pad_numbers_are_jumpers no)
		(fp_line
			(start -0.299974 0.150114)
			(end -0.299974 -0.150114)
			(stroke
				(width 0.1)
				(type default)
			)
			(layer "F.Fab")
		)
		(fp_line
			(start 0.299974 0.150114)
			(end -0.299974 0.150114)
			(stroke
				(width 0.1)
				(type default)
			)
			(layer "F.Fab")
		)
		(fp_line
			(start -0.299974 -0.150114)
			(end 0.299974 -0.150114)
			(stroke
				(width 0.1)
				(type default)
			)
			(layer "F.Fab")
		)
		(fp_line
			(start 0.299974 -0.150114)
			(end 0.299974 0.150114)
			(stroke
				(width 0.1)
				(type default)
			)
			(layer "F.Fab")
		)
		(pad "1" smd rect
			(at -0.2667 0 270)
			(size 0.3048 0.381)
			(layers "F.Cu" "F.Mask" "F.Paste")
			(net "P5E_CPU1_P1_TX_C_DN<8>")
		)
		(pad "2" smd rect
			(at 0.2667 0 270)
			(size 0.3048 0.381)
			(layers "F.Cu" "F.Mask" "F.Paste")
			(net "P5E_CPU1_P1_TX_DN<8>")
		)
	)
)
